(kicad_pcb
	(version 20260206)
	(generator "pcbnew")
	(generator_version "10.0")
	(general
		(thickness 1.6)
		(legacy_teardrops no)
	)
	(paper "A4")
	(title_block
		(title "01162023_DA0F0TEBIF0_F0T_Expander_BD_F_brd_V02_OCP.brd")
		(comment 1 "Grand Teton / footprints 8650-8656 of 9728")
	)
	(layers
		(0 "F.Cu" signal "TOP")
		(4 "In1.Cu" signal "GND")
		(6 "In2.Cu" signal "VCC")
		(8 "In3.Cu" signal "VCC1")
		(10 "In4.Cu" signal "GND1")
		(12 "In5.Cu" signal "IN1")
		(14 "In6.Cu" signal "GND2")
		(16 "In7.Cu" signal "IN2")
		(18 "In8.Cu" signal "GND3")
		(20 "In9.Cu" signal "IN3")
		(22 "In10.Cu" signal "GND4")
		(24 "In11.Cu" signal "IN4")
		(26 "In12.Cu" signal "GND5")
		(28 "In13.Cu" signal "IN5")
		(30 "In14.Cu" signal "GND6")
		(32 "In15.Cu" signal "IN6")
		(34 "In16.Cu" signal "GND7")
		(2 "B.Cu" signal "BOTTOM")
		(9 "F.Adhes" user "F.Adhesive")
		(11 "B.Adhes" user "B.Adhesive")
		(13 "F.Paste" user "Package Geometry/Pastemask Top")
		(15 "B.Paste" user "Package Geometry/Pastemask Bottom")
		(5 "F.SilkS" user "Ref Des/Silkscreen Top")
		(7 "B.SilkS" user "Ref Des/Silkscreen Bottom")
		(1 "F.Mask" user "Board Geometry/Soldermask Top")
		(3 "B.Mask" user "Board Geometry/Soldermask Bottom")
		(17 "Dwgs.User" user "User.Drawings")
		(19 "Cmts.User" user "User.Comments")
		(21 "Eco1.User" user "User.Eco1")
		(23 "Eco2.User" user "User.Eco2")
		(25 "Edge.Cuts" user "Board Geometry/Outline")
		(27 "Margin" user)
		(31 "F.CrtYd" user "Package Geometry/Place Bound Top")
		(29 "B.CrtYd" user "Package Geometry/Place Bound Bottom")
		(35 "F.Fab" user "Ref Des/Assembly Top")
		(33 "B.Fab" user "Ref Des/Assembly Bottom")
	)
	(footprint ""
		(layer "B.Cu")
		(at 391.263886 -285.853632)
		(property "Reference" "C3512"
			(at 0 0 0)
			(layer "B.SilkS")
			(hide yes)
			(effects
				(font
					(size 1.27 1.27)
				)
				(justify mirror)
			)
		)
		(property "Value" ""
			(at 0 0 0)
			(layer "B.Fab")
			(effects
				(font
					(size 1.27 1.27)
				)
				(justify mirror)
			)
		)
		(duplicate_pad_numbers_are_jumpers no)
		(fp_line
			(start -1.2954 -0.5842)
			(end -1.2954 0.5842)
			(stroke
				(width 0.1524)
				(type default)
			)
			(layer "B.SilkS")
		)
		(fp_line
			(start -1.2954 0.5842)
			(end 1.2954 0.5842)
			(stroke
				(width 0.1524)
				(type default)
			)
			(layer "B.SilkS")
		)
		(fp_line
			(start 1.2954 -0.5842)
			(end -1.2954 -0.5842)
			(stroke
				(width 0.1524)
				(type default)
			)
			(layer "B.SilkS")
		)
		(fp_line
			(start 1.2954 0.5842)
			(end 1.2954 -0.5842)
			(stroke
				(width 0.1524)
				(type default)
			)
			(layer "B.SilkS")
		)
		(fp_line
			(start -1.1938 -0.4064)
			(end -1.1938 0.4064)
			(stroke
				(width 0.1)
				(type default)
			)
			(layer "B.Fab")
		)
		(fp_line
			(start -1.1938 0.4064)
			(end -0.8636 0.4064)
			(stroke
				(width 0.1)
				(type default)
			)
			(layer "B.Fab")
		)
		(fp_line
			(start -0.8636 -0.4572)
			(end -0.8636 -0.4064)
			(stroke
				(width 0.1)
				(type default)
			)
			(layer "B.Fab")
		)
		(fp_line
			(start -0.8636 -0.4064)
			(end -1.1938 -0.4064)
			(stroke
				(width 0.1)
				(type default)
			)
			(layer "B.Fab")
		)
		(fp_line
			(start -0.8636 0.4064)
			(end -0.8636 0.4572)
			(stroke
				(width 0.1)
				(type default)
			)
			(layer "B.Fab")
		)
		(fp_line
			(start -0.8636 0.4572)
			(end 0.8636 0.4572)
			(stroke
				(width 0.1)
				(type default)
			)
			(layer "B.Fab")
		)
		(fp_line
			(start 0.8636 -0.4572)
			(end -0.8636 -0.4572)
			(stroke
				(width 0.1)
				(type default)
			)
			(layer "B.Fab")
		)
		(fp_line
			(start 0.8636 -0.4064)
			(end 0.8636 -0.4572)
			(stroke
				(width 0.1)
				(type default)
			)
			(layer "B.Fab")
		)
		(fp_line
			(start 0.8636 0.4064)
			(end 1.1938 0.4064)
			(stroke
				(width 0.1)
				(type default)
			)
			(layer "B.Fab")
		)
		(fp_line
			(start 0.8636 0.4572)
			(end 0.8636 0.4064)
			(stroke
				(width 0.1)
				(type default)
			)
			(layer "B.Fab")
		)
		(fp_line
			(start 1.1938 -0.4064)
			(end 0.8636 -0.4064)
			(stroke
				(width 0.1)
				(type default)
			)
			(layer "B.Fab")
		)
		(fp_line
			(start 1.1938 0.4064)
			(end 1.1938 -0.4064)
			(stroke
				(width 0.1)
				(type default)
			)
			(layer "B.Fab")
		)
		(pad "1" smd rect
			(at 0.7366 0 270)
			(size 0.7112 0.8128)
			(layers "B.Cu" "B.Mask" "B.Paste")
			(net "P1V8_PEX")
		)
		(pad "2" smd rect
			(at -0.7366 0 270)
			(size 0.7112 0.8128)
			(layers "B.Cu" "B.Mask" "B.Paste")
			(net "GND")
		)
	)
	(footprint ""
		(layer "B.Cu")
		(at 212.409532 -230.65359 90)
		(property "Reference" "R6320"
			(at 0 0 90)
			(layer "B.SilkS")
			(hide yes)
			(effects
				(font
					(size 1.27 1.27)
				)
				(justify mirror)
			)
		)
		(property "Value" ""
			(at 0 0 90)
			(layer "B.Fab")
			(effects
				(font
					(size 1.27 1.27)
				)
				(justify mirror)
			)
		)
		(duplicate_pad_numbers_are_jumpers no)
		(fp_line
			(start 0.7874 -0.4064)
			(end -0.7874 -0.4064)
			(stroke
				(width 0.1524)
				(type default)
			)
			(layer "B.SilkS")
		)
		(fp_line
			(start -0.7874 -0.4064)
			(end -0.7874 0.4064)
			(stroke
				(width 0.1524)
				(type default)
			)
			(layer "B.SilkS")
		)
		(fp_line
			(start 0.7874 0.4064)
			(end 0.7874 -0.4064)
			(stroke
				(width 0.1524)
				(type default)
			)
			(layer "B.SilkS")
		)
		(fp_line
			(start -0.7874 0.4064)
			(end 0.7874 0.4064)
			(stroke
				(width 0.1524)
				(type default)
			)
			(layer "B.SilkS")
		)
		(fp_line
			(start 0.67945 -0.305054)
			(end 0.12065 -0.305054)
			(stroke
				(width 0.1)
				(type default)
			)
			(layer "B.Fab")
		)
		(fp_line
			(start 0.12065 -0.305054)
			(end 0.12065 -0.2794)
			(stroke
				(width 0.1)
				(type default)
			)
			(layer "B.Fab")
		)
		(fp_line
			(start -0.12065 -0.3048)
			(end -0.67945 -0.3048)
			(stroke
				(width 0.1)
				(type default)
			)
			(layer "B.Fab")
		)
		(fp_line
			(start -0.67945 -0.3048)
			(end -0.67945 0.3048)
			(stroke
				(width 0.1)
				(type default)
			)
			(layer "B.Fab")
		)
		(fp_line
			(start 0.12065 -0.2794)
			(end -0.12065 -0.2794)
			(stroke
				(width 0.1)
				(type default)
			)
			(layer "B.Fab")
		)
		(fp_line
			(start -0.12065 -0.2794)
			(end -0.12065 -0.3048)
			(stroke
				(width 0.1)
				(type default)
			)
			(layer "B.Fab")
		)
		(fp_line
			(start 0.12065 0.2794)
			(end 0.12065 0.3048)
			(stroke
				(width 0.1)
				(type default)
			)
			(layer "B.Fab")
		)
		(fp_line
			(start -0.120396 0.2794)
			(end 0.12065 0.2794)
			(stroke
				(width 0.1)
				(type default)
			)
			(layer "B.Fab")
		)
		(fp_line
			(start 0.67945 0.3048)
			(end 0.67945 -0.305054)
			(stroke
				(width 0.1)
				(type default)
			)
			(layer "B.Fab")
		)
		(fp_line
			(start 0.12065 0.3048)
			(end 0.67945 0.3048)
			(stroke
				(width 0.1)
				(type default)
			)
			(layer "B.Fab")
		)
		(fp_line
			(start -0.120396 0.3048)
			(end -0.120396 0.2794)
			(stroke
				(width 0.1)
				(type default)
			)
			(layer "B.Fab")
		)
		(fp_line
			(start -0.67945 0.3048)
			(end -0.120396 0.3048)
			(stroke
				(width 0.1)
				(type default)
			)
			(layer "B.Fab")
		)
		(pad "1" smd circle
			(at 0.40005 0 270)
			(size 0 0)
			(layers "B.Cu" "B.Mask" "B.Paste")
			(net "SMB_PEX0_SDA")
		)
		(pad "2" smd circle
			(at -0.40005 0 270)
			(size 0 0)
			(layers "B.Cu" "B.Mask" "B.Paste")
			(net "SMB_PEX0_MUX_SDA")
		)
	)
	(footprint ""
		(layer "B.Cu")
		(at 421.571674 -114.592608)
		(property "Reference" "C959"
			(at 0 0 0)
			(layer "B.SilkS")
			(hide yes)
			(effects
				(font
					(size 1.27 1.27)
				)
				(justify mirror)
			)
		)
		(property "Value" ""
			(at 0 0 0)
			(layer "B.Fab")
			(effects
				(font
					(size 1.27 1.27)
				)
				(justify mirror)
			)
		)
		(duplicate_pad_numbers_are_jumpers no)
		(fp_line
			(start -0.7874 -0.4064)
			(end -0.7874 0.4064)
			(stroke
				(width 0.1524)
				(type default)
			)
			(layer "B.SilkS")
		)
		(fp_line
			(start -0.7874 0.4064)
			(end 0.7874 0.4064)
			(stroke
				(width 0.1524)
				(type default)
			)
			(layer "B.SilkS")
		)
		(fp_line
			(start 0.7874 -0.4064)
			(end -0.7874 -0.4064)
			(stroke
				(width 0.1524)
				(type default)
			)
			(layer "B.SilkS")
		)
		(fp_line
			(start 0.7874 0.4064)
			(end 0.7874 -0.4064)
			(stroke
				(width 0.1524)
				(type default)
			)
			(layer "B.SilkS")
		)
		(fp_line
			(start -0.67945 -0.3048)
			(end -0.67945 0.3048)
			(stroke
				(width 0.1)
				(type default)
			)
			(layer "B.Fab")
		)
		(fp_line
			(start -0.67945 0.3048)
			(end -0.120396 0.3048)
			(stroke
				(width 0.1)
				(type default)
			)
			(layer "B.Fab")
		)
		(fp_line
			(start -0.12065 -0.3048)
			(end -0.67945 -0.3048)
			(stroke
				(width 0.1)
				(type default)
			)
			(layer "B.Fab")
		)
		(fp_line
			(start -0.12065 -0.2794)
			(end -0.12065 -0.3048)
			(stroke
				(width 0.1)
				(type default)
			)
			(layer "B.Fab")
		)
		(fp_line
			(start -0.120396 0.2794)
			(end 0.12065 0.2794)
			(stroke
				(width 0.1)
				(type default)
			)
			(layer "B.Fab")
		)
		(fp_line
			(start -0.120396 0.3048)
			(end -0.120396 0.2794)
			(stroke
				(width 0.1)
				(type default)
			)
			(layer "B.Fab")
		)
		(fp_line
			(start 0.12065 -0.305054)
			(end 0.12065 -0.2794)
			(stroke
				(width 0.1)
				(type default)
			)
			(layer "B.Fab")
		)
		(fp_line
			(start 0.12065 -0.2794)
			(end -0.12065 -0.2794)
			(stroke
				(width 0.1)
				(type default)
			)
			(layer "B.Fab")
		)
		(fp_line
			(start 0.12065 0.2794)
			(end 0.12065 0.3048)
			(stroke
				(width 0.1)
				(type default)
			)
			(layer "B.Fab")
		)
		(fp_line
			(start 0.12065 0.3048)
			(end 0.67945 0.3048)
			(stroke
				(width 0.1)
				(type default)
			)
			(layer "B.Fab")
		)
		(fp_line
			(start 0.67945 -0.305054)
			(end 0.12065 -0.305054)
			(stroke
				(width 0.1)
				(type default)
			)
			(layer "B.Fab")
		)
		(fp_line
			(start 0.67945 0.3048)
			(end 0.67945 -0.305054)
			(stroke
				(width 0.1)
				(type default)
			)
			(layer "B.Fab")
		)
		(pad "1" smd circle
			(at 0.40005 0 180)
			(size 0 0)
			(layers "B.Cu" "B.Mask" "B.Paste")
			(net "P3V3_NIC7")
		)
		(pad "2" smd circle
			(at -0.40005 0 180)
			(size 0 0)
			(layers "B.Cu" "B.Mask" "B.Paste")
			(net "GND")
		)
	)
	(footprint ""
		(layer "B.Cu")
		(at 49.1998 -292.574726 180)
		(property "Reference" "C1106"
			(at 0 0 0)
			(layer "B.SilkS")
			(hide yes)
			(effects
				(font
					(size 1.27 1.27)
				)
				(justify mirror)
			)
		)
		(property "Value" ""
			(at 0 0 0)
			(layer "B.Fab")
			(effects
				(font
					(size 1.27 1.27)
				)
				(justify mirror)
			)
		)
		(duplicate_pad_numbers_are_jumpers no)
		(fp_line
			(start 0.299974 0.150114)
			(end 0.299974 -0.150114)
			(stroke
				(width 0.1)
				(type default)
			)
			(layer "B.Fab")
		)
		(fp_line
			(start 0.299974 -0.150114)
			(end -0.299974 -0.150114)
			(stroke
				(width 0.1)
				(type default)
			)
			(layer "B.Fab")
		)
		(fp_line
			(start -0.299974 0.150114)
			(end 0.299974 0.150114)
			(stroke
				(width 0.1)
				(type default)
			)
			(layer "B.Fab")
		)
		(fp_line
			(start -0.299974 -0.150114)
			(end -0.299974 0.150114)
			(stroke
				(width 0.1)
				(type default)
			)
			(layer "B.Fab")
		)
		(pad "1" smd rect
			(at 0.2667 0)
			(size 0.3048 0.381)
			(layers "B.Cu" "B.Mask" "B.Paste")
			(net "P0V8_PEX0")
		)
		(pad "2" smd rect
			(at -0.2667 0)
			(size 0.3048 0.381)
			(layers "B.Cu" "B.Mask" "B.Paste")
			(net "GND")
		)
	)
	(footprint ""
		(layer "B.Cu")
		(at 185.250074 -300.174914 180)
		(property "Reference" "C3188"
			(at 0 0 0)
			(layer "B.SilkS")
			(hide yes)
			(effects
				(font
					(size 1.27 1.27)
				)
				(justify mirror)
			)
		)
		(property "Value" ""
			(at 0 0 0)
			(layer "B.Fab")
			(effects
				(font
					(size 1.27 1.27)
				)
				(justify mirror)
			)
		)
		(duplicate_pad_numbers_are_jumpers no)
		(fp_line
			(start 0.299974 0.150114)
			(end 0.299974 -0.150114)
			(stroke
				(width 0.1)
				(type default)
			)
			(layer "B.Fab")
		)
		(fp_line
			(start 0.299974 -0.150114)
			(end -0.299974 -0.150114)
			(stroke
				(width 0.1)
				(type default)
			)
			(layer "B.Fab")
		)
		(fp_line
			(start -0.299974 0.150114)
			(end 0.299974 0.150114)
			(stroke
				(width 0.1)
				(type default)
			)
			(layer "B.Fab")
		)
		(fp_line
			(start -0.299974 -0.150114)
			(end -0.299974 0.150114)
			(stroke
				(width 0.1)
				(type default)
			)
			(layer "B.Fab")
		)
		(pad "1" smd rect
			(at 0.2667 0)
			(size 0.3048 0.381)
			(layers "B.Cu" "B.Mask" "B.Paste")
			(net "P1V8_VDDA_PEX1")
		)
		(pad "2" smd rect
			(at -0.2667 0)
			(size 0.3048 0.381)
			(layers "B.Cu" "B.Mask" "B.Paste")
			(net "GND")
		)
	)
	(footprint ""
		(layer "B.Cu")
		(at 29.741622 -224.75063 180)
		(property "Reference" "R6164"
			(at 0 0 0)
			(layer "B.SilkS")
			(hide yes)
			(effects
				(font
					(size 1.27 1.27)
				)
				(justify mirror)
			)
		)
		(property "Value" ""
			(at 0 0 0)
			(layer "B.Fab")
			(effects
				(font
					(size 1.27 1.27)
				)
				(justify mirror)
			)
		)
		(duplicate_pad_numbers_are_jumpers no)
		(fp_line
			(start 0.7874 0.4064)
			(end 0.7874 -0.4064)
			(stroke
				(width 0.1524)
				(type default)
			)
			(layer "B.SilkS")
		)
		(fp_line
			(start 0.7874 -0.4064)
			(end -0.7874 -0.4064)
			(stroke
				(width 0.1524)
				(type default)
			)
			(layer "B.SilkS")
		)
		(fp_line
			(start -0.7874 0.4064)
			(end 0.7874 0.4064)
			(stroke
				(width 0.1524)
				(type default)
			)
			(layer "B.SilkS")
		)
		(fp_line
			(start -0.7874 -0.4064)
			(end -0.7874 0.4064)
			(stroke
				(width 0.1524)
				(type default)
			)
			(layer "B.SilkS")
		)
		(fp_line
			(start 0.67945 0.3048)
			(end 0.67945 -0.305054)
			(stroke
				(width 0.1)
				(type default)
			)
			(layer "B.Fab")
		)
		(fp_line
			(start 0.67945 -0.305054)
			(end 0.12065 -0.305054)
			(stroke
				(width 0.1)
				(type default)
			)
			(layer "B.Fab")
		)
		(fp_line
			(start 0.12065 0.3048)
			(end 0.67945 0.3048)
			(stroke
				(width 0.1)
				(type default)
			)
			(layer "B.Fab")
		)
		(fp_line
			(start 0.12065 0.2794)
			(end 0.12065 0.3048)
			(stroke
				(width 0.1)
				(type default)
			)
			(layer "B.Fab")
		)
		(fp_line
			(start 0.12065 -0.2794)
			(end -0.12065 -0.2794)
			(stroke
				(width 0.1)
				(type default)
			)
			(layer "B.Fab")
		)
		(fp_line
			(start 0.12065 -0.305054)
			(end 0.12065 -0.2794)
			(stroke
				(width 0.1)
				(type default)
			)
			(layer "B.Fab")
		)
		(fp_line
			(start -0.120396 0.3048)
			(end -0.120396 0.2794)
			(stroke
				(width 0.1)
				(type default)
			)
			(layer "B.Fab")
		)
		(fp_line
			(start -0.120396 0.2794)
			(end 0.12065 0.2794)
			(stroke
				(width 0.1)
				(type default)
			)
			(layer "B.Fab")
		)
		(fp_line
			(start -0.12065 -0.2794)
			(end -0.12065 -0.3048)
			(stroke
				(width 0.1)
				(type default)
			)
			(layer "B.Fab")
		)
		(fp_line
			(start -0.12065 -0.3048)
			(end -0.67945 -0.3048)
			(stroke
				(width 0.1)
				(type default)
			)
			(layer "B.Fab")
		)
		(fp_line
			(start -0.67945 0.3048)
			(end -0.120396 0.3048)
			(stroke
				(width 0.1)
				(type default)
			)
			(layer "B.Fab")
		)
		(fp_line
			(start -0.67945 -0.3048)
			(end -0.67945 0.3048)
			(stroke
				(width 0.1)
				(type default)
			)
			(layer "B.Fab")
		)
		(pad "1" smd circle
			(at 0.40005 0)
			(size 0 0)
			(layers "B.Cu" "B.Mask" "B.Paste")
			(net "SPI_PEX0_RST_R_N")
		)
		(pad "2" smd circle
			(at -0.40005 0)
			(size 0 0)
			(layers "B.Cu" "B.Mask" "B.Paste")
			(net "GND")
		)
	)
	(footprint ""
		(layer "B.Cu")
		(at 305.471576 -115.608608)
		(property "Reference" "C934"
			(at 0 0 0)
			(layer "B.SilkS")
			(hide yes)
			(effects
				(font
					(size 1.27 1.27)
				)
				(justify mirror)
			)
		)
		(property "Value" ""
			(at 0 0 0)
			(layer "B.Fab")
			(effects
				(font
					(size 1.27 1.27)
				)
				(justify mirror)
			)
		)
		(duplicate_pad_numbers_are_jumpers no)
		(fp_line
			(start -0.7874 -0.4064)
			(end -0.7874 0.4064)
			(stroke
				(width 0.1524)
				(type default)
			)
			(layer "B.SilkS")
		)
		(fp_line
			(start -0.7874 0.4064)
			(end 0.7874 0.4064)
			(stroke
				(width 0.1524)
				(type default)
			)
			(layer "B.SilkS")
		)
		(fp_line
			(start 0.7874 -0.4064)
			(end -0.7874 -0.4064)
			(stroke
				(width 0.1524)
				(type default)
			)
			(layer "B.SilkS")
		)
		(fp_line
			(start 0.7874 0.4064)
			(end 0.7874 -0.4064)
			(stroke
				(width 0.1524)
				(type default)
			)
			(layer "B.SilkS")
		)
		(fp_line
			(start -0.67945 -0.3048)
			(end -0.67945 0.3048)
			(stroke
				(width 0.1)
				(type default)
			)
			(layer "B.Fab")
		)
		(fp_line
			(start -0.67945 0.3048)
			(end -0.120396 0.3048)
			(stroke
				(width 0.1)
				(type default)
			)
			(layer "B.Fab")
		)
		(fp_line
			(start -0.12065 -0.3048)
			(end -0.67945 -0.3048)
			(stroke
				(width 0.1)
				(type default)
			)
			(layer "B.Fab")
		)
		(fp_line
			(start -0.12065 -0.2794)
			(end -0.12065 -0.3048)
			(stroke
				(width 0.1)
				(type default)
			)
			(layer "B.Fab")
		)
		(fp_line
			(start -0.120396 0.2794)
			(end 0.12065 0.2794)
			(stroke
				(width 0.1)
				(type default)
			)
			(layer "B.Fab")
		)
		(fp_line
			(start -0.120396 0.3048)
			(end -0.120396 0.2794)
			(stroke
				(width 0.1)
				(type default)
			)
			(layer "B.Fab")
		)
		(fp_line
			(start 0.12065 -0.305054)
			(end 0.12065 -0.2794)
			(stroke
				(width 0.1)
				(type default)
			)
			(layer "B.Fab")
		)
		(fp_line
			(start 0.12065 -0.2794)
			(end -0.12065 -0.2794)
			(stroke
				(width 0.1)
				(type default)
			)
			(layer "B.Fab")
		)
		(fp_line
			(start 0.12065 0.2794)
			(end 0.12065 0.3048)
			(stroke
				(width 0.1)
				(type default)
			)
			(layer "B.Fab")
		)
		(fp_line
			(start 0.12065 0.3048)
			(end 0.67945 0.3048)
			(stroke
				(width 0.1)
				(type default)
			)
			(layer "B.Fab")
		)
		(fp_line
			(start 0.67945 -0.305054)
			(end 0.12065 -0.305054)
			(stroke
				(width 0.1)
				(type default)
			)
			(layer "B.Fab")
		)
		(fp_line
			(start 0.67945 0.3048)
			(end 0.67945 -0.305054)
			(stroke
				(width 0.1)
				(type default)
			)
			(layer "B.Fab")
		)
		(pad "1" smd circle
			(at 0.40005 0 180)
			(size 0 0)
			(layers "B.Cu" "B.Mask" "B.Paste")
			(net "P3V3_NIC5")
		)
		(pad "2" smd circle
			(at -0.40005 0 180)
			(size 0 0)
			(layers "B.Cu" "B.Mask" "B.Paste")
			(net "GND")
		)
	)
)
